%FSTAX23Y23*%
%MOIN*%
%SFA1B1*%

%IPPOS*%
%ADD17C,0.006000*%
%ADD19C,0.008000*%
%ADD21C,0.005000*%
%ADD153C,0.020000*%
%ADD159C,0.061020*%
%ADD161C,0.075000*%
%ADD169R,0.055000X0.055000*%
%ADD171C,0.016000*%
%LNgrandmaster-1*%
%LPD*%
G54D17*
X02083Y01411D02*
X02084Y01412D01*
Y03895*
X02084Y03896*
G54D19*
X02528Y02618D02*
D01*
X02527Y02618*
X02527Y02617*
X02527Y02617*
X02526Y02616*
X02526Y02616*
X02526Y02615*
X02526Y02615*
X02526Y02614*
X02525Y02614*
X02525Y02613*
X02525Y02613*
X02525Y02613*
X02664Y02755D02*
D01*
X02665Y02755*
X02665Y02756*
X02666Y02756*
X02666Y02757*
X02666Y02757*
X02666Y02758*
X02666Y02758*
X02667Y02759*
X02667Y02759*
X02667Y0276*
X02667Y02761*
X02667Y02761*
X02552Y02615D02*
D01*
X02551Y02614*
X02551Y02614*
X02551Y02613*
X0255Y02613*
X0255Y02612*
X0255Y02612*
X0255Y02611*
X0255Y02611*
X02549Y0261*
X02549Y0261*
X02549Y02609*
X02549Y02609*
X02684Y02747D02*
D01*
X02685Y02748*
X02685Y02748*
X02685Y02748*
X02686Y02749*
X02686Y02749*
X02686Y0275*
X02686Y0275*
X02686Y02751*
X02686Y02752*
X02686Y02752*
X02687Y02753*
X02687Y02753*
X02294Y03901D02*
D01*
X02294Y03901*
X02294Y039*
X02294Y039*
X02294Y03899*
X02294Y03899*
X02294Y03898*
X02295Y03898*
X02295Y03897*
X02295Y03897*
X02296Y03896*
X02296Y03896*
X02296Y03896*
X02579Y03609D02*
D01*
X02579Y0361*
X02579Y0361*
X02579Y03611*
X02579Y03612*
X02579Y03612*
X02579Y03613*
X02578Y03613*
X02578Y03614*
X02578Y03614*
X02577Y03614*
X02577Y03615*
X02577Y03615*
X02505Y0262D02*
X02653Y02767D01*
Y02981*
X02462Y03172D02*
X02653Y02981D01*
X02525Y02463D02*
Y02613D01*
X02528Y02618D02*
X02664Y02755D01*
X02667Y02761D02*
Y03155D01*
X02525Y02613D02*
D01*
X02505Y02442D02*
Y0262D01*
X02386Y02769D02*
X02494Y02661D01*
X02386Y02769D02*
Y03019D01*
X02687Y02753D02*
Y03353D01*
X02549Y01755D02*
Y02609D01*
D01*
X02552Y02615D02*
X02684Y02747D01*
X02638Y02667D02*
X02692Y02721D01*
X02579Y03486D02*
Y03609D01*
X02294Y03901D02*
Y04126D01*
X02296Y03896D02*
X02577Y03615D01*
X02579Y03609D02*
Y03609D01*
X05577Y02214D02*
X0558D01*
X05584Y02218*
X05586*
X03492Y02357D02*
Y03296D01*
X03497Y02344D02*
X03499Y02342D01*
X01363Y01786D02*
X01393Y01816D01*
X01363Y00832D02*
Y01786D01*
X0099Y00687D02*
X01217D01*
X01363Y00832*
X03542Y02415D02*
Y03319D01*
Y02415D02*
X03604Y02353D01*
X03509Y03323D02*
X03523Y0331D01*
Y01467D02*
Y0331D01*
Y01467D02*
X03549Y01441D01*
X03653Y03293D02*
X03695Y03251D01*
Y017D02*
X0372Y01675D01*
X03695Y017D02*
Y03251D01*
X03604Y0209D02*
Y02353D01*
X01574Y0242D02*
X01619Y02375D01*
Y02121D02*
Y02375D01*
X01574Y0242D02*
Y03596D01*
X01568Y02067D02*
Y02389D01*
X01549Y02465D02*
D01*
Y02407D02*
Y02465D01*
Y02407D02*
X01568Y02389D01*
X01549Y02465D02*
Y03621D01*
X03197Y01714D02*
Y02969D01*
X03197Y0297*
X03491Y03297D02*
X03492Y03296D01*
X03224Y03229D02*
X0323Y03235D01*
X03224Y01661D02*
Y03229D01*
X03358Y033D02*
Y03448D01*
X03068Y03395D02*
X03072Y03391D01*
X03064Y03399D02*
X03068Y03395D01*
X03072Y02242D02*
Y03391D01*
X02998Y02618D02*
Y02972D01*
X03021Y02995D02*
Y03821D01*
X02998Y02972D02*
X03021Y02995D01*
X02993Y02985D02*
Y03751D01*
X02998Y02618D02*
X03013Y02603D01*
X03014Y03828D02*
X03021Y03821D01*
X02979Y02971D02*
X02993Y02985D01*
X03013Y02314D02*
Y02603D01*
X03014Y03828D02*
Y03831D01*
X03056Y01811D02*
Y02226D01*
X03072Y02242*
X03252Y01661D02*
Y03293D01*
X03263Y03303*
X02527Y03294D02*
X02667Y03155D01*
X02634Y03406D02*
X02687Y03353D01*
X02527Y03294D02*
Y03434D01*
X02385Y03019D02*
X02386Y03019D01*
X02385Y03019D02*
Y03298D01*
X02362Y02688D02*
X02429Y02621D01*
X02527Y03434D02*
X02579Y03486D01*
X02505Y02442D02*
X02519Y02428D01*
Y02227D02*
Y02428D01*
X02638Y0253D02*
Y02667D01*
X02665Y02398D02*
Y02503D01*
X02638Y0253D02*
X02665Y02503D01*
X02645Y02274D02*
Y02379D01*
X02665Y02398*
X02625Y01771D02*
X02626Y0177D01*
X02625Y01771D02*
Y01777D01*
X02624Y01777D02*
X02625Y01777D01*
X02624Y01777D02*
Y02461D01*
X02004Y01336D02*
Y03816D01*
X02028Y01361D02*
X02029Y01362D01*
X02579Y0179D02*
Y02281D01*
X02475Y02291D02*
X02478Y02288D01*
X02446Y02275D02*
X0245Y02279D01*
Y02282*
X02446Y01437D02*
Y02275D01*
X02409Y01967D02*
Y02283D01*
X02362Y03298D02*
X02459Y03396D01*
X02434Y03546D02*
X02459Y03521D01*
Y03396D02*
Y03521D01*
X02253Y03847D02*
X02479Y03622D01*
X02385Y03298D02*
X02479Y03391D01*
Y03622*
X02341Y0343D02*
X02389Y03478D01*
X02341Y02447D02*
Y0343D01*
X02389Y03478D02*
Y03481D01*
X02362Y02688D02*
Y03298D01*
X02341Y02447D02*
X02389Y02398D01*
X02253Y03847D02*
Y04086D01*
X02299Y01916D02*
Y03491D01*
X02254Y03536D02*
X02299Y03491D01*
X02143Y04106D02*
X02146Y04103D01*
X01979Y04106D02*
X02143D01*
X01925Y0416D02*
X01979Y04106D01*
X01925Y0416D02*
D01*
X01836Y04249D02*
X01925Y0416D01*
X01586Y04314D02*
X01625Y04276D01*
X01393Y04314D02*
X01586D01*
X01625Y04276D02*
X01881D01*
X01345Y04175D02*
Y04266D01*
X01393Y04314*
X02205Y032D02*
Y04144D01*
X02143Y04206D02*
X02205Y04144D01*
X01951Y04206D02*
X02143D01*
X01881Y04276D02*
X01951Y04206D01*
X02043Y04257D02*
X02163D01*
X02294Y04126*
X01681Y04249D02*
X01836D01*
X01631Y04046D02*
Y04199D01*
X01681Y04249*
X01478Y03892D02*
X01631Y04046D01*
X05634Y021D02*
Y02236D01*
Y00947D02*
Y021D01*
X04327Y02307D02*
X04534Y021D01*
X05634*
X04039Y02406D02*
X04062Y02428D01*
X01459Y03147D02*
Y03463D01*
X01478Y03482D02*
Y03892D01*
X01459Y03463D02*
X01478Y03482D01*
X02979Y0246D02*
Y02971D01*
X02967Y02447D02*
X02979Y0246D01*
X02274Y01506D02*
Y02286D01*
X02272Y02289D02*
X02274Y02286D01*
X02272Y02289D02*
Y02463D01*
X02252Y02613D02*
X02259Y02621D01*
X03329Y01826D02*
Y01936D01*
X03324Y01941D02*
X03329Y01936D01*
X03439Y0187D02*
Y01874D01*
X03438Y01875D02*
X03439Y01874D01*
X05577Y02214D02*
X05578Y02214D01*
Y02489*
X02694Y02284D02*
X02702Y02292D01*
Y02293*
X02694Y01481D02*
Y02284D01*
X02389Y01948D02*
Y02398D01*
X02384Y01943D02*
X02389Y01948D01*
X02384Y01941D02*
Y01943D01*
X03744Y01711D02*
Y03261D01*
Y01711D02*
X03774Y01681D01*
Y01667D02*
Y01681D01*
X03773Y01666D02*
X03774Y01667D01*
X05578Y0089D02*
X05634Y00947D01*
X0392Y03102D02*
X03939Y03121D01*
X0392Y01685D02*
Y03102D01*
Y01685D02*
X03924Y01681D01*
Y01536D02*
Y01681D01*
X02604Y01734D02*
Y02431D01*
X02259Y02621D02*
Y03261D01*
X03374Y0327D02*
Y03273D01*
X03368Y03264D02*
X03374Y0327D01*
X03368Y0305D02*
Y03264D01*
X04062Y02428D02*
Y02595D01*
X03789Y03235D02*
X03806D01*
X03769Y03215D02*
X03789Y03235D01*
X03769Y01726D02*
Y03215D01*
Y01726D02*
X03803Y01692D01*
Y01691D02*
Y01692D01*
X0138Y04202D02*
X01438Y0426D01*
X0138Y03617D02*
Y04202D01*
Y03617D02*
X0144Y03557D01*
X03622Y02588D02*
Y03486D01*
Y02588D02*
X03623Y02587D01*
X03394Y02011D02*
Y03447D01*
X03509Y03323D02*
Y03766D01*
X03519Y03776*
Y04071*
X03504Y04086D02*
X03519Y04071D01*
X03344Y02996D02*
Y03286D01*
Y02265D02*
Y02996D01*
X03436Y01999D02*
Y03457D01*
Y01999D02*
X03439Y01996D01*
X03492Y02357D02*
X03501Y02348D01*
X03497Y02344D02*
X03501Y02348D01*
X03344Y03286D02*
X03358Y033D01*
X03302Y01977D02*
Y03344D01*
X03298Y01973D02*
X03302Y01977D01*
X03298Y01971D02*
Y01973D01*
X03834Y01481D02*
Y02321D01*
X03799Y02356D02*
X03834Y02321D01*
X0384Y02861D02*
X03854Y02875D01*
X0384Y02368D02*
Y02861D01*
Y02368D02*
X03894Y02314D01*
X03799Y02356D02*
Y03201D01*
X03824Y02361D02*
X03864Y02321D01*
Y01511D02*
Y02321D01*
X03324Y01941D02*
X03394Y02011D01*
X03604Y0209D02*
X03613Y02081D01*
Y01735D02*
Y02081D01*
X03589Y01711D02*
X03613Y01735D01*
X03498Y02341D02*
X03499Y02342D01*
X02478Y00937D02*
Y02288D01*
X02985Y02287D02*
X03013Y02314D01*
X02205Y01299D02*
Y02408D01*
Y01299D02*
X02206Y01298D01*
X02205Y02468D02*
Y032D01*
Y02468D02*
X02225Y02447D01*
Y02429D02*
Y02447D01*
X02205Y02408D02*
X02225Y02429D01*
X02229Y02586D02*
Y03498D01*
X02234Y03503*
Y03506*
X02502Y01316D02*
Y0221D01*
X02519Y02227*
X0292Y01537D02*
Y02428D01*
X02919Y01536D02*
X0292Y01537D01*
X02942Y02286D02*
X02955D01*
X02967Y02298*
Y02447*
X03342Y02263D02*
X03344Y02265D01*
X02643Y01711D02*
X02648Y01716D01*
X02643Y01616D02*
Y01711D01*
X02648Y01716D02*
Y02265D01*
X02645Y02274D02*
X02647Y02272D01*
Y02266D02*
Y02272D01*
Y02266D02*
X02648Y02265D01*
X02665Y01641D02*
X02666Y0164D01*
X02665Y01641D02*
Y02291D01*
X02726Y01599D02*
Y02293D01*
X02719Y01592D02*
X02726Y01599D01*
X02719Y01591D02*
Y01592D01*
X01884Y02071D02*
Y03601D01*
X02029Y01362D02*
Y03836D01*
X02059Y01386D02*
Y03871D01*
X01754Y02126D02*
Y03661D01*
X01549Y03621D02*
D01*
X01719Y01536D02*
X01779Y01596D01*
Y04156*
X02894Y01561D02*
Y02431D01*
X03894Y01566D02*
Y02314D01*
X0372Y01675D02*
X03724D01*
X03438Y01875D02*
X03469Y01906D01*
X03854Y02875D02*
Y03151D01*
X03829Y02873D02*
Y03176D01*
X03824Y02361D02*
Y02868D01*
X03829Y02873*
X03392Y01949D02*
X03439Y01996D01*
X03392Y01871D02*
Y01949D01*
X03469Y01906D02*
Y03456D01*
G54D21*
X02496Y0039D02*
D01*
X02497Y0039*
X02498Y0039*
X02499Y0039*
X025Y0039*
X02501Y00391*
X02502Y00391*
X02503Y00392*
X02504Y00392*
X02505Y00393*
X02506Y00393*
X02507Y00394*
X02507Y00395*
X02508Y00396*
X02509Y00396*
X02509Y00397*
X0251Y00398*
X0251Y00399*
X02511Y004*
X02511Y00401*
X02511Y00402*
X02511Y00403*
X02511Y00404*
X02511Y00405*
X02466Y0073D02*
D01*
X02459Y00722*
X02453Y00715*
X02447Y00707*
X02442Y00698*
X02438Y0069*
X02434Y00681*
X02431Y00671*
X02428Y00662*
X02426Y00652*
X02425Y00643*
X02425Y00633*
X02425Y0063*
Y00436D02*
D01*
X02425Y00433*
X02425Y0043*
X02426Y00427*
X02427Y00423*
X02428Y0042*
X02429Y00417*
X0243Y00414*
X02432Y00412*
X02434Y00409*
X02436Y00406*
X02438Y00404*
X0244Y00402*
X02443Y004*
X02445Y00398*
X02448Y00396*
X02451Y00394*
X02454Y00393*
X02457Y00392*
X0246Y00391*
X02463Y0039*
X02466Y0039*
X0247Y0039*
X02471Y0039*
X02953Y00399D02*
D01*
X02953Y00399*
X02953Y00399*
X02953Y00399*
X02953Y00399*
X02953Y00399*
X02974Y00391D02*
D01*
X02976Y00391*
X02977Y0039*
X02978Y0039*
X02979Y0039*
X02981Y0039*
X02982Y0039*
X02983Y0039*
X02954Y00399D02*
D01*
X02957Y00397*
X02961Y00395*
X02964Y00394*
X02968Y00393*
X02971Y00392*
X02974Y00391*
X02925Y0047D02*
D01*
X02925Y00462*
X02926Y00455*
X02927Y00449*
X02929Y00442*
X02931Y00435*
X02933Y00429*
X02936Y00422*
X0294Y00416*
X02944Y0041*
X02948Y00405*
X02953Y00399*
X02953Y00399*
X02984Y00391D02*
D01*
X02984Y0039*
X02983Y0039*
X02983Y0039*
X02984Y00391D02*
D01*
X02988Y00391*
X02991Y00391*
X02995Y00392*
X02999Y00393*
X03002Y00394*
X03006Y00396*
X03009Y00398*
X03012Y004*
X03015Y00402*
X03018Y00404*
X03019Y00405*
X02953Y00399D02*
D01*
X02954Y00399*
X02954Y00399*
X02954Y00399*
X02954Y00399*
X02954Y00399*
X02974Y00391D02*
D01*
X02974Y00391*
X02974Y00391*
X02974Y00391*
X02979Y00409D02*
D01*
X02979Y00409*
X02979Y00409*
X02979Y00409*
X0298Y00409*
X0298Y00409*
X0298Y00409*
X02966Y00443D02*
D01*
X02966Y00443*
X02965Y00443*
X02965Y00443*
X02964Y00443*
X02964Y00442*
X02963Y00442*
X02963Y00442*
X02962Y00442*
X02962Y00441*
X02961Y00441*
X02961Y00441*
X02961Y0044*
X0296Y0044*
X0296Y0044*
X0296Y00439*
X02959Y00439*
X02959Y00438*
X02959Y00438*
X02959Y00437*
X02959Y00437*
X02959Y00436*
X02959Y00436*
Y00435*
X02959Y00435*
X02959Y00434*
X02959Y00434*
X02959Y00433*
X02959Y00433*
X02975Y00412D02*
D01*
X02976Y00411*
X02977Y00411*
X02977Y0041*
X02978Y0041*
X02979Y00409*
X02966Y00443D02*
D01*
X02967Y00443*
X02967Y00443*
X02968Y00443*
X02968Y00443*
X02969Y00443*
X02969Y00444*
X0297Y00444*
X0297Y00444*
X02971Y00444*
X02971Y00445*
X02971Y00445*
X02972Y00445*
X02972Y00446*
X02972Y00446*
X02973Y00447*
X02973Y00447*
X02973Y00448*
X02973Y00448*
X02974Y00449*
X02974Y00449*
X02974Y0045*
X02974Y0045*
Y00451*
X02974Y00451*
X02974Y00452*
X02974Y00452*
X02973Y00453*
X02973Y00453*
X02973Y00454*
X02973Y00454*
X02972Y00455*
X02972Y00455*
X02972Y00455*
X02971Y00456*
X02971Y00456*
X02971Y00456*
X0297Y00457*
X0297Y00457*
X02969Y00457*
X02969Y00457*
X02968Y00458*
X02968Y00458*
X02967Y00458*
X02967Y00458*
X02966Y00458*
X02945Y00473D02*
D01*
X02944Y00473*
X02944Y00473*
X02943Y00473*
X02943Y00473*
X02942Y00472*
X02942Y00472*
X02941Y00472*
X02941Y00472*
X0294Y00471*
X0294Y00471*
X0294Y00471*
X02939Y0047*
X02939Y0047*
X02939Y0047*
X02938Y00469*
X02938Y00469*
X02938Y00468*
X02938Y00468*
X02937Y00467*
X02937Y00467*
X02937Y00466*
X02937Y00466*
Y00465*
X02937Y00465*
X02937Y00464*
X02937Y00464*
X02938Y00463*
X02938Y00463*
X02938Y00462*
X02938Y00462*
X02939Y00461*
X02939Y00461*
X02939Y0046*
X0294Y0046*
X0294Y0046*
X0294Y00459*
X02941Y00459*
X02941Y00459*
X02942Y00459*
X02942Y00458*
X02943Y00458*
X02943Y00458*
X02944Y00458*
X02944Y00458*
X02945Y00458*
X02955Y00473D02*
D01*
X02955Y00473*
X02956Y00473*
X02956Y00473*
X02957Y00473*
X02957Y00473*
X02958Y00474*
X02958Y00474*
X02959Y00474*
X02959Y00474*
X02959Y00475*
X0296Y00475*
X0296Y00475*
X02961Y00476*
X02961Y00476*
X02961Y00477*
X02961Y00477*
X02962Y00478*
X02962Y00478*
X02962Y00479*
X02962Y00479*
X02962Y0048*
X02962Y0048*
Y00481*
X02962Y00481*
X02962Y00482*
X02962Y00482*
X02962Y00483*
X02962Y00483*
X02961Y00484*
X02961Y00484*
X02961Y00485*
X02961Y00485*
X0296Y00485*
X0296Y00486*
X02959Y00486*
X02959Y00486*
X02959Y00487*
X02958Y00487*
X02958Y00487*
X02957Y00487*
X02957Y00488*
X02956Y00488*
X02956Y00488*
X02955Y00488*
X02955Y00488*
X02938Y00493D02*
D01*
X02938Y00492*
X02938Y00492*
X02938Y00491*
X02938Y00491*
X02939Y00491*
X02939Y0049*
X0294Y0049*
X0294Y00489*
X0294Y00489*
X02941Y00489*
X02941Y00489*
X02942Y00488*
X02942Y00488*
X02943Y00488*
X02943Y00488*
X02944Y00488*
X02944Y00488*
X02945Y00488*
X02847Y00436D02*
D01*
X02847Y00437*
X02846Y00437*
X02846Y00437*
X02845Y00438*
X02845Y00438*
X02844Y00438*
X02844Y00438*
X02843Y00438*
X02843Y00439*
X02842Y00439*
X02842Y00439*
X02841Y00439*
X02841Y00439*
X0284Y00438*
X0284Y00438*
X02839Y00438*
X02839Y00438*
X02838Y00438*
X02838Y00438*
X02837Y00437*
X02837Y00437*
X02837Y00437*
X02836Y00436*
X02851Y00432D02*
D01*
X02851Y00432*
X02852Y00432*
X02852Y00431*
X02853Y00431*
X02853Y00431*
X02854Y00431*
X02854Y00431*
X02855Y0043*
X02855Y0043*
X02856Y0043*
X02856Y0043*
X02857Y0043*
X02857Y0043*
X02858Y0043*
X02858Y0043*
X02859Y00431*
X02859Y00431*
X0286Y00431*
X0286Y00431*
X02861Y00432*
X02861Y00432*
X02861Y00432*
X02862Y00432*
D01*
X02862Y00433*
X02862Y00433*
X02863Y00434*
X02863Y00434*
X02863Y00435*
X02863Y00435*
X02863Y00436*
X02864Y00436*
X02864Y00437*
X02864Y00437*
X02864Y00438*
X02864Y00438*
X02864Y00439*
X02864Y00439*
X02864Y0044*
X02863Y0044*
X02863Y00441*
X02863Y00441*
X02863Y00442*
X02862Y00442*
X02862Y00442*
X02862Y00443*
X02862Y00443*
X02856Y0046D02*
D01*
X02855Y00459*
X02855Y00459*
X02855Y00458*
X02854Y00458*
X02854Y00457*
X02854Y00457*
X02854Y00457*
X02854Y00456*
X02854Y00455*
X02853Y00455*
X02853Y00454*
X02853Y00454*
X02854Y00453*
X02854Y00453*
X02854Y00452*
X02854Y00452*
X02854Y00451*
X02854Y00451*
X02855Y0045*
X02855Y0045*
X02855Y0045*
X02855Y00449*
X02856Y00449*
X02866Y0046D02*
D01*
X02866Y0046*
X02865Y0046*
X02865Y00461*
X02865Y00461*
X02864Y00461*
X02864Y00461*
X02863Y00461*
X02863Y00462*
X02862Y00462*
X02862Y00462*
X02861Y00462*
X02861Y00462*
X0286Y00462*
X0286Y00462*
X02859Y00462*
X02858Y00461*
X02858Y00461*
X02858Y00461*
X02857Y00461*
X02857Y0046*
X02856Y0046*
X02856Y0046*
X02856Y0046*
X02872Y00454D02*
D01*
X02873Y00453*
X02873Y00453*
X02873Y00453*
X02874Y00452*
X02874Y00452*
X02875Y00452*
X02875Y00452*
X02876Y00452*
X02876Y00452*
X02877Y00451*
X02877Y00451*
X02878Y00451*
X02878Y00451*
X02879Y00452*
X02879Y00452*
X0288Y00452*
X0288Y00452*
X02881Y00452*
X02881Y00452*
X02882Y00453*
X02882Y00453*
X02883Y00453*
X02883Y00454*
D01*
X02883Y00454*
X02884Y00454*
X02884Y00455*
X02884Y00455*
X02884Y00456*
X02885Y00456*
X02885Y00457*
X02885Y00457*
X02885Y00458*
X02885Y00458*
X02885Y00459*
X02885Y00459*
X02885Y0046*
X02885Y0046*
X02885Y00461*
X02885Y00461*
X02884Y00462*
X02884Y00462*
X02884Y00463*
X02884Y00463*
X02883Y00464*
X02883Y00464*
X02883Y00464*
X02879Y00479D02*
D01*
X02878Y00478*
X02878Y00478*
X02878Y00478*
X02878Y00477*
X02877Y00477*
X02877Y00476*
X02877Y00476*
X02877Y00475*
X02877Y00475*
X02877Y00474*
X02877Y00474*
X02877Y00473*
X02877Y00473*
X02877Y00472*
X02877Y00472*
X02877Y00471*
X02877Y00471*
X02877Y0047*
X02878Y0047*
X02878Y00469*
X02878Y00469*
X02879Y00468*
X02879Y00468*
X02803Y00407D02*
D01*
X02803Y00406*
X02803Y00404*
X02804Y00403*
X02804Y00401*
X02805Y004*
X02805Y00398*
X02806Y00397*
X02807Y00396*
X02808Y00394*
X02809Y00393*
X02809Y00393*
X02811Y0043D02*
D01*
X0281Y00428*
X02809Y00426*
X02808Y00425*
X02806Y00423*
X02806Y00421*
X02805Y00419*
X02804Y00417*
X02804Y00415*
X02803Y00413*
X02803Y00411*
X02803Y00409*
X02803Y00407*
X0287Y00489D02*
D01*
X02871Y00489*
X02871Y00489*
X02871Y00489*
X02871Y0049*
X02871Y0049*
X02872Y0049*
X02872Y00491*
X02872Y00491*
X02872Y00491*
X02872Y00492*
X02872Y00492*
X02872Y00492*
X02809Y00393D02*
D01*
X0281Y00392*
X02812Y00391*
X02813Y0039*
X02814Y00389*
X02816Y00389*
X02817Y00388*
X02818Y00387*
X0282Y00387*
X02822Y00387*
X02823Y00387*
X02825Y00387*
X02826Y00387*
X02828Y00387*
X02829Y00387*
X02831Y00387*
X02832Y00388*
X02834Y00388*
X02835Y00389*
X02836Y0039*
X02838Y00391*
X02839Y00392*
X0284Y00393*
X02881Y00482D02*
D01*
X02881Y00482*
X02881Y00482*
X02881Y00482*
X02881Y00482*
X02881Y00482*
X02734Y00406D02*
D01*
X02734Y00407*
X02735Y00407*
X02735Y00407D02*
D01*
X02735Y00407*
X02735Y00408*
X02735Y00408*
X02735Y00408*
X02736Y00408*
X02736Y00408*
X0274Y00435D02*
D01*
X0274Y00436*
X0274Y00436*
X0274Y00437*
X0274Y00438*
X0274Y00438*
X02739Y00439*
X02739Y00439*
X02739Y00439*
X02739Y0044*
X02738Y0044*
X02738Y00441*
X02738Y00441*
X02737Y00441*
X02737Y00442*
X02736Y00442*
X02736Y00442*
X02735Y00442*
X02735Y00443*
X02734Y00443*
X02734Y00443*
X02733Y00443*
X02733Y00443*
X02733Y00443*
Y00458D02*
D01*
X02732Y00458*
X02732Y00458*
X02731Y00458*
X0273Y00458*
X0273Y00457*
X0273Y00457*
X02729Y00457*
X02729Y00457*
X02728Y00457*
X02728Y00456*
X02727Y00456*
X02727Y00455*
X02727Y00455*
X02726Y00455*
X02726Y00454*
X02726Y00454*
X02726Y00453*
X02725Y00453*
X02725Y00452*
X02725Y00452*
X02725Y00451*
X02725Y00451*
Y0045*
X02725Y0045*
X02725Y00449*
X02725Y00449*
X02725Y00448*
X02726Y00448*
X02726Y00447*
X02726Y00447*
X02726Y00446*
X02727Y00446*
X02727Y00445*
X02727Y00445*
X02728Y00445*
X02728Y00444*
X02729Y00444*
X02729Y00444*
X0273Y00444*
X0273Y00443*
X0273Y00443*
X02731Y00443*
X02732Y00443*
X02732Y00443*
X02733Y00443*
X02734Y00458D02*
D01*
X02734Y00458*
X02735Y00458*
X02735Y00458*
X02736Y00458*
X02736Y00458*
X02737Y00459*
X02737Y00459*
X02738Y00459*
X02738Y00459*
X02738Y0046*
X02739Y0046*
X02739Y0046*
X02739Y00461*
X0274Y00461*
X0274Y00462*
X0274Y00462*
X02741Y00463*
X02741Y00463*
X02741Y00464*
X02741Y00464*
X02741Y00465*
X02741Y00465*
Y00466*
X02741Y00466*
X02741Y00467*
X02741Y00467*
X02741Y00468*
X02741Y00468*
X0274Y00469*
X0274Y00469*
X0274Y0047*
X02739Y0047*
X02739Y0047*
X02739Y00471*
X02738Y00471*
X02738Y00472*
X02738Y00472*
X02737Y00472*
X02737Y00472*
X02736Y00472*
X02736Y00473*
X02735Y00473*
X02735Y00473*
X02734Y00473*
X02734Y00473*
X02732Y00488D02*
D01*
X02731Y00488*
X02731Y00488*
X0273Y00488*
X0273Y00488*
X02729Y00487*
X02729Y00487*
X02728Y00487*
X02728Y00487*
X02727Y00487*
X02727Y00486*
X02727Y00486*
X02726Y00485*
X02726Y00485*
X02725Y00485*
X02725Y00484*
X02725Y00484*
X02725Y00483*
X02725Y00483*
X02724Y00482*
X02724Y00482*
X02724Y00481*
X02724Y00481*
Y0048*
X02724Y0048*
X02724Y00479*
X02724Y00479*
X02725Y00478*
X02725Y00478*
X02725Y00477*
X02725Y00477*
X02725Y00476*
X02726Y00476*
X02726Y00475*
X02727Y00475*
X02727Y00475*
X02727Y00474*
X02728Y00474*
X02728Y00474*
X02729Y00474*
X02729Y00473*
X0273Y00473*
X0273Y00473*
X02731Y00473*
X02731Y00473*
X02732Y00473*
X02734Y00488D02*
D01*
X02734Y00488*
X02735Y00488*
X02735Y00488*
X02736Y00488*
X02736Y00488*
X02737Y00489*
X02737Y00489*
X02738Y00489*
X02738Y00489*
X02738Y0049*
X02739Y0049*
X02739Y0049*
X02739Y00491*
X0274Y00491*
X0274Y00492*
X0274Y00492*
X02741Y00493*
X02741Y00493*
X02741Y00494*
X02741Y00494*
X02741Y00495*
X02741Y00495*
Y00496*
X02741Y00496*
X02741Y00497*
X02741Y00497*
X02741Y00498*
X02741Y00498*
X0274Y00499*
X0274Y00499*
X0274Y005*
X02739Y005*
X02739Y005*
X02739Y00501*
X02738Y00501*
X02738Y00502*
X02738Y00502*
X02737Y00502*
X02737Y00502*
X02736Y00502*
X02736Y00503*
X02735Y00503*
X02735Y00503*
X02734Y00503*
X02734Y00503*
X02731Y00518D02*
D01*
X0273Y00518*
X0273Y00518*
X02729Y00518*
X02728Y00518*
X02728Y00517*
X02727Y00517*
X02727Y00517*
X02727Y00517*
X02726Y00517*
X02726Y00516*
X02725Y00516*
X02725Y00515*
X02725Y00515*
X02724Y00515*
X02724Y00514*
X02724Y00514*
X02724Y00513*
X02723Y00513*
X02723Y00512*
X02723Y00512*
X02723Y00511*
X02723Y00511*
Y0051*
X02723Y0051*
X02723Y00509*
X02723Y00509*
X02723Y00508*
X02724Y00508*
X02724Y00507*
X02724Y00507*
X02724Y00506*
X02725Y00506*
X02725Y00505*
X02725Y00505*
X02726Y00505*
X02726Y00504*
X02727Y00504*
X02727Y00504*
X02727Y00504*
X02728Y00503*
X02728Y00503*
X02729Y00503*
X0273Y00503*
X0273Y00503*
X02731Y00503*
X02733Y00518D02*
D01*
X02733Y00518*
X02734Y00518*
X02734Y00518*
X02735Y00518*
X02735Y00518*
X02736Y00519*
X02736Y00519*
X02737Y00519*
X02737Y00519*
X02737Y0052*
X02738Y0052*
X02738Y0052*
X02738Y00521*
X02739Y00521*
X02739Y00522*
X02739Y00522*
X0274Y00523*
X0274Y00523*
X0274Y00524*
X0274Y00524*
X0274Y00525*
X0274Y00525*
X0274Y00525*
X02704Y00405D02*
D01*
X02705Y00404*
X02706Y00403*
X02708Y00402*
X02709Y00402*
X0271Y00401*
X02711Y004*
X02713Y004*
X02714Y004*
X02716Y00399*
X02717Y00399*
X02718Y00399*
X0272Y00399*
X02721Y00399*
X02723Y004*
X02724Y004*
X02725Y004*
X02727Y00401*
X02728Y00401*
X02729Y00402*
X0273Y00403*
X02732Y00404*
X02733Y00405*
X02734Y00406*
X02409Y00366D02*
D01*
X02409Y00365*
X0241Y00365*
X0241Y00365*
X02411Y00364*
X02411Y00364*
X02419Y00362D02*
D01*
X02419Y00362*
X0242Y00362*
X0242Y00362*
X02421Y00362*
X02421Y00362*
X02422Y00362*
X02422Y00362*
X02423Y00362*
X02423Y00362*
X02424Y00363*
X02424Y00363*
X02425Y00363*
X02425Y00363*
X02425Y00364*
X02426Y00364*
X02426Y00365*
X02427Y00365*
X02427Y00365*
X02427Y00366*
X02427Y00366*
X02428Y00367*
X02428Y00367*
X02428Y00368*
X02428Y00368*
X02428Y00369*
X02428Y00369*
X02428Y00369*
X02443Y00372D02*
D01*
X02443Y00372*
X02443Y00373*
X02443Y00373*
X02443Y00374*
X02443Y00374*
X02442Y00375*
X02442Y00375*
X02442Y00376*
X02442Y00376*
X02441Y00377*
X02441Y00377*
X02441Y00377*
X0244Y00378*
X0244Y00378*
X02439Y00378*
X02439Y00378*
X02438Y00379*
X02438Y00379*
X02437Y00379*
X02437Y00379*
X02436Y00379*
X02436Y00379*
X02435*
X02435Y00379*
X02434Y00379*
X02434Y00379*
X02433Y00379*
X02433Y00379*
X02432Y00378*
X02432Y00378*
X02431Y00378*
X02431Y00378*
X02431Y00377*
X0243Y00377*
X0243Y00377*
X02429Y00376*
X02429Y00376*
X02429Y00375*
X02429Y00375*
X02429Y00374*
X02428Y00374*
X02428Y00373*
X02428Y00373*
X02428Y00372*
X02428Y00372*
X02443Y00361D02*
D01*
X02443Y00361*
X02443Y0036*
X02443Y0036*
X02443Y00359*
X02444Y00359*
X02444Y00358*
X02444Y00358*
X02444Y00357*
X02444Y00357*
X02445Y00356*
X02445Y00356*
X02446Y00356*
X02446Y00355*
X02446Y00355*
X02447Y00355*
X02447Y00355*
X02448Y00354*
X02448Y00354*
X02449Y00354*
X02397Y00376D02*
D01*
X02401Y00372*
X02405Y00369*
X02409Y00366*
X02409Y00366*
X02444Y00505D02*
D01*
X02444Y00505*
X02444Y00504*
X02445Y00504*
X02445Y00503*
X02445Y00503*
X02445Y00502*
X02445Y00502*
X02446Y00501*
X02446Y00501*
X02446Y005*
X02446Y005*
X02447Y005*
X02447Y00499*
X02448Y00499*
X02448Y00499*
X02449Y00498*
X02449Y00498*
X0245Y00498*
X0245Y00498*
X02451Y00498*
X02451Y00498*
X02452Y00498*
X02452Y00498*
X02456Y00483D02*
D01*
X02457Y00483*
X02457Y00483*
X02458Y00483*
X02458Y00483*
X02459Y00483*
X02459Y00483*
X0246Y00484*
X0246Y00484*
X02461Y00484*
X02461Y00484*
X02461Y00485*
X02462Y00485*
X02462Y00486*
X02462Y00486*
X02463Y00486*
X02463Y00487*
X02463Y00487*
X02463Y00488*
X02463Y00488*
X02464Y00489*
X02464Y00489*
X02464Y0049*
Y0049*
X02464Y00491*
X02464Y00491*
X02463Y00492*
X02463Y00492*
X02463Y00493*
X02463Y00493*
X02463Y00494*
X02462Y00494*
X02462Y00495*
X02462Y00495*
X02461Y00496*
X02461Y00496*
X02461Y00496*
X0246Y00497*
X0246Y00497*
X02459Y00497*
X02459Y00497*
X02458Y00497*
X02458Y00497*
X02457Y00498*
X02457Y00498*
X02456Y00498*
X02442Y00483D02*
D01*
X02442Y00483*
X02441Y00483*
X02441Y00482*
X0244Y00482*
X0244Y00482*
X02439Y00482*
X02439Y00482*
X02438Y00482*
X02438Y00481*
X02437Y00481*
X02437Y00481*
X02437Y0048*
X02436Y0048*
X02436Y00479*
X02436Y00479*
X02435Y00478*
X02435Y00478*
X02435Y00477*
X02435Y00477*
X02435Y00476*
X02435Y00476*
X02435Y00475*
Y00475*
X02435Y00474*
X02435Y00474*
X02435Y00473*
X02435Y00473*
X02435Y00472*
X02435Y00472*
X02436Y00471*
X02436Y00471*
X02436Y00471*
X02437Y0047*
X02437Y0047*
X02437Y00469*
X02438Y00469*
X02438Y00469*
X02439Y00469*
X02439Y00468*
X0244Y00468*
X0244Y00468*
X02441Y00468*
X02441Y00468*
X02442Y00468*
X02442Y00468*
X02458Y00453D02*
D01*
X02459Y00453*
X02459Y00453*
X0246Y00453*
X0246Y00453*
X02461Y00453*
X02461Y00453*
X02462Y00454*
X02462Y00454*
X02463Y00454*
X02463Y00454*
X02464Y00455*
X02464Y00455*
X02464Y00456*
X02465Y00456*
X02465Y00456*
X02465Y00457*
X02465Y00457*
X02465Y00458*
X02466Y00458*
X02466Y00459*
X02466Y00459*
X02466Y0046*
Y0046*
X02466Y00461*
X02466Y00461*
X02466Y00462*
X02465Y00462*
X02465Y00463*
X02465Y00463*
X02465Y00464*
X02465Y00464*
X02464Y00465*
X02464Y00465*
X02464Y00466*
X02463Y00466*
X02463Y00466*
X02462Y00467*
X02462Y00467*
X02461Y00467*
X02461Y00467*
X0246Y00467*
X0246Y00467*
X02459Y00468*
X02459Y00468*
X02458Y00468*
X02452Y00453D02*
D01*
X02451Y00453*
X02451Y00453*
X0245Y00452*
X0245Y00452*
X02449Y00452*
X02449Y00452*
X02448Y00452*
X02448Y00452*
X02447Y00451*
X02447Y00451*
X02447Y00451*
X02446Y0045*
X02446Y0045*
X02446Y00449*
X02445Y00449*
X02445Y00448*
X02445Y00448*
X02445Y00447*
X02445Y00447*
X02444Y00446*
X02444Y00446*
X02444Y00445*
X02444Y00445*
Y00423D02*
D01*
X02444Y00423*
X02444Y00423*
X02444Y00422*
X02445Y00422*
X02445Y00421*
X02445Y00421*
X02445Y00421*
X02445Y0042*
X02445Y0042*
X02446Y0042*
X02446Y0042*
X02446Y00419*
X02446Y00419*
X02474Y00722D02*
D01*
X02469Y00717*
X02465Y00711*
X02461Y00706*
X02457Y007*
X02454Y00693*
X02451Y00687*
X02449Y0068*
X02447Y00674*
X02446Y00667*
X02445Y0066*
X02444Y00653*
X02444Y00651*
X02453Y00414D02*
D01*
X02453Y00414*
X02453Y00414*
X02453Y00414*
X02453Y00414*
X02453Y00414*
X02453Y00414D02*
D01*
X02454Y00413*
X02455Y00412*
X02456Y00412*
X02457Y00411*
X02458Y00411*
X02459Y0041*
X0246Y0041*
X02461Y0041*
X02463Y0041*
X02464Y0041*
X02465Y0041*
X02466Y0041*
X02467Y0041*
X02468Y0041*
X02469Y0041*
X02881Y00482D02*
D01*
X02882Y00482*
X02882Y00482*
X02882Y00482*
X02882Y00483*
X02882Y00483*
X02883Y00483*
X02883Y00484*
X02883Y00484*
X02883Y00484*
X02883Y00485*
X02883Y00485*
X02883Y00485*
X02872Y0077D02*
D01*
X02872Y00772*
X02872Y00775*
X02871Y00777*
X02871Y0078*
X0287Y00782*
X02869Y00784*
X02868Y00786*
X02867Y00789*
X02865Y00791*
X02864Y00793*
X02862Y00794*
X02862Y00795*
X02849Y00403D02*
D01*
X02849Y00403*
X0285Y00403*
X0285Y00403*
X02851Y00403*
X02851Y00403*
X02852Y00404*
X02852Y00404*
X02853Y00404*
X02853Y00404*
X02853Y00405*
X02854Y00405*
X02854Y00405*
X02848Y00403D02*
D01*
X02847Y00403*
X02847Y00403*
X02846Y00403*
X02846Y00403*
X02846Y00403*
X02845Y00402*
X02845Y00402*
X02844Y00402*
X02844Y00402*
X02844Y00402*
X02843Y00401*
X02843Y00401*
D01*
X02843Y00401*
X02843Y00401*
X02843Y004*
X02842Y004*
X02842Y004*
X02842Y00399*
X02842Y00399*
X02842Y00398*
X02842Y00398*
X02842Y00398*
X02842Y00397*
X02842Y00397*
X0284Y00393D02*
D01*
X0284Y00393*
X0284Y00393*
X02841Y00393*
X02841Y00394*
X02841Y00394*
X02841Y00394*
X02841Y00395*
X02841Y00395*
X02842Y00395*
X02842Y00396*
X02842Y00396*
X02842Y00396*
X02735Y00392D02*
D01*
X02737Y00393*
X02739Y00395*
X0274Y00396*
X02742Y00398*
X02744Y004*
X02745Y00402*
X02746Y00404*
X02748Y00407*
X02749Y00409*
X02749Y00411*
X0275Y00414*
X02751Y00416*
X02751Y00418*
X02751Y00421*
X02751Y00422*
X02671Y00399D02*
D01*
X02674Y00396*
X02676Y00394*
X02679Y00392*
X02682Y0039*
X02686Y00389*
X02689Y00387*
X02692Y00386*
X02696Y00385*
X02699Y00384*
X02703Y00384*
X02706Y00384*
X0271Y00384*
X02713Y00384*
X02717Y00385*
X0272Y00386*
X02724Y00387*
X02727Y00388*
X0273Y00389*
X02733Y00391*
X02735Y00392*
X02759Y00795D02*
D01*
X02758Y00793*
X02757Y00792*
X02756Y0079*
X02755Y00788*
X02754Y00787*
X02753Y00785*
X02752Y00783*
X02752Y00781*
X02751Y00779*
X02751Y00777*
X02751Y00775*
X02751Y00775*
X02823Y00973D02*
D01*
X02822Y00972*
X02822Y00971*
X02821Y0097*
X0282Y00969*
X0282Y00968*
X02819Y00966*
X02819Y00965*
X02818Y00964*
X02818Y00963*
X02818Y00962*
X02818Y0096*
X02818Y0096*
X02893Y00795D02*
D01*
X02892Y00793*
X0289Y00791*
X02889Y00789*
X02887Y00787*
X02886Y00785*
X02885Y00783*
X02884Y0078*
X02884Y00778*
X02883Y00776*
X02883Y00773*
X02883Y00771*
X02883Y0077*
X0274Y00775D02*
D01*
X0274Y00777*
X0274Y00779*
X02739Y00781*
X02739Y00782*
X02738Y00784*
X02738Y00786*
X02737Y00788*
X02736Y0079*
X02735Y00791*
X02733Y00793*
X02732Y00794*
X02732Y00795*
X0235Y00405D02*
D01*
X0235Y00405*
X0235Y00405*
X0235Y00405*
X0235Y00405*
X02351Y00405*
X02351Y00404*
X02351Y00404*
X02351Y00404*
X02351Y00404*
X02351Y00404*
X02351Y00404*
X02352Y00404*
X02363Y00403D02*
D01*
X02362Y00403*
X02362Y00403*
X02362Y00404*
X02361Y00404*
X02361Y00404*
X02361Y00404*
X02361Y00404*
X0236Y00404*
X0236Y00404*
X0236Y00404*
X02359Y00404*
X02359Y00404*
X02364Y00399D02*
D01*
X02364Y004*
X02364Y004*
X02364Y004*
X02364Y00401*
X02364Y00401*
X02364Y00401*
X02363Y00402*
X02363Y00402*
X02363Y00402*
X02363Y00403*
X02363Y00403*
X02363Y00403*
X02364Y00397D02*
D01*
X02364Y00396*
X02364Y00396*
X02364Y00395*
X02364Y00394*
X02365Y00393*
X02365Y00393*
X02365Y00392*
X02366Y00392*
X02366Y00391*
X02367Y0039*
X02367Y0039*
X02367Y0039*
X02389Y00368D02*
D01*
X02393Y00364*
X02398Y0036*
X02403Y00357*
X02408Y00353*
X02413Y00351*
X02419Y00348*
X02424Y00347*
X0243Y00345*
X02436Y00344*
X02442Y00343*
X02448Y00343*
X02449Y00343*
X02535D02*
D01*
X02536Y00343*
X02536Y00343*
X02537Y00343*
X02538Y00343*
X02539Y00343*
X02539Y00344*
X0254Y00344*
X02541Y00344*
X02541Y00345*
X02542Y00345*
X02543Y00346*
X02543Y00346*
X02585Y00388D02*
D01*
X0259Y00394*
X02595Y004*
X02599Y00406*
X02603Y00413*
X02607Y0042*
X0261Y00427*
X02612Y00434*
X02614Y00442*
X02616Y00449*
X02617Y00457*
X02617Y00465*
X02617Y00466*
X02625Y00795D02*
D01*
X02624Y00793*
X02623Y00792*
X02622Y0079*
X02621Y00788*
X0262Y00787*
X02619Y00785*
X02618Y00783*
X02618Y00781*
X02618Y00779*
X02617Y00777*
X02617Y00775*
X02617Y00775*
X02388Y00404D02*
D01*
X02388Y00404*
X02388Y00404*
X02388Y00404*
X02388Y00404*
X02388Y00404*
X02389Y00405*
X02389Y00405*
X02389Y00405*
X02389Y00405*
X02389Y00405*
X02389Y00405*
X02389Y00405*
X0238Y00404D02*
D01*
X0238Y00404*
X02379Y00404*
X02379Y00404*
X02379Y00404*
X02378Y00404*
X02378Y00404*
X02378Y00404*
X02377Y00404*
X02377Y00403*
X02377Y00403*
X02377Y00403*
X02377Y00403*
D01*
X02376Y00403*
X02376Y00402*
X02376Y00402*
X02376Y00402*
X02376Y00401*
X02375Y00401*
X02375Y00401*
X02375Y004*
X02375Y004*
X02375Y004*
X02375Y00399*
X02375Y00399*
D01*
X02375Y00399*
X02375Y00399*
X02375Y00398*
X02375Y00398*
X02375Y00398*
X02376Y00397*
X02376Y00397*
X02376Y00397*
X02376Y00396*
X02376Y00396*
X02376Y00396*
X02377Y00396*
X02577D02*
D01*
X02582Y00401*
X02586Y00406*
X0259Y00412*
X02594Y00418*
X02597Y00424*
X026Y00431*
X02602Y00437*
X02604Y00444*
X02605Y00451*
X02606Y00458*
X02606Y00465*
X02606Y00467*
Y00775D02*
D01*
X02606Y00777*
X02606Y00779*
X02606Y00781*
X02605Y00782*
X02604Y00784*
X02604Y00786*
X02603Y00788*
X02602Y0079*
X02601Y00791*
X026Y00793*
X02598Y00794*
X02598Y00795*
X02818Y0096D02*
D01*
X02818Y00959*
X02818Y00958*
X02818Y00956*
X02819Y00955*
X02819Y00954*
X0282Y00953*
X0282Y00952*
X02821Y00951*
X02821Y0095*
X02822Y00949*
X02823Y00948*
X02823Y00947*
X02925Y00789D02*
D01*
X02924Y00796*
X02924Y00803*
X02923Y0081*
X02921Y00817*
X02919Y00823*
X02916Y0083*
X02913Y00836*
X0291Y00842*
X02906Y00848*
X02901Y00853*
X02897Y00858*
X02895Y0086*
X02807Y00958D02*
D01*
X02807Y00956*
X02807Y00955*
X02808Y00953*
X02808Y00951*
X02808Y0095*
X02809Y00948*
X0281Y00947*
X02811Y00945*
X02811Y00944*
X02812Y00943*
X02814Y00942*
X02814Y00941*
X02807Y00958D02*
D01*
X02807Y00959*
X02807Y00961*
X02806Y00963*
X02806Y00964*
X02806Y00966*
X02805Y00967*
X02804Y00969*
X02803Y0097*
X02803Y00972*
X02802Y00973*
X028Y00974*
X028Y00974*
X02936Y00808D02*
D01*
X02936Y00813*
X02935Y00817*
X02934Y00822*
X02933Y00826*
X02932Y0083*
X0293Y00834*
X02928Y00839*
X02926Y00842*
X02923Y00846*
X02921Y0085*
X02918Y00853*
X02917Y00854*
X02689Y0096D02*
D01*
X02689Y00961*
X02689Y00963*
X02688Y00964*
X02688Y00965*
X02688Y00966*
X02687Y00967*
X02687Y00968*
X02686Y0097*
X02685Y00971*
X02685Y00972*
X02684Y00972*
X02684Y00973*
Y00947D02*
D01*
X02684Y00948*
X02685Y00949*
X02686Y0095*
X02687Y00951*
X02687Y00953*
X02688Y00954*
X02688Y00955*
X02688Y00956*
X02689Y00957*
X02689Y00958*
X02689Y0096*
X02689Y0096*
X02707Y00974D02*
D01*
X02706Y00973*
X02705Y00972*
X02704Y0097*
X02703Y00969*
X02702Y00968*
X02701Y00966*
X02701Y00965*
X027Y00963*
X027Y00961*
X027Y0096*
X027Y00958*
X027Y00958*
X02693Y00941D02*
D01*
X02694Y00942*
X02695Y00944*
X02696Y00945*
X02697Y00946*
X02698Y00948*
X02698Y00949*
X02699Y00951*
X02699Y00953*
X027Y00954*
X027Y00956*
X027Y00957*
X027Y00958*
X02478Y0039D02*
X02496D01*
X02478D02*
X02478D01*
X02425Y0063D02*
Y00436D01*
X02471Y0039D02*
X02478D01*
X02984Y00391D02*
D01*
X02953Y00399D02*
X02953Y00399D01*
X02983Y0039D02*
D01*
X02925Y0047D02*
Y00789D01*
X02953Y00399D02*
D01*
X02936Y00498D02*
Y00808D01*
X02938Y00493D02*
D01*
X0298Y00409D02*
D01*
X02962Y00424D02*
X02975Y00412D01*
X02959Y00433D02*
X02962Y00424D01*
X02959Y00433D02*
D01*
X02966Y00443D02*
D01*
X02945Y00458D02*
X02966D01*
X02945Y00473D02*
X02955D01*
X02945Y00488D02*
X02955D01*
X02937Y00495D02*
X02938Y00493D01*
X02936Y00498D02*
X02937Y00495D01*
X02818Y00406D02*
X02819Y00407D01*
X02816Y00412D02*
X02816Y00411D01*
X02816Y00412D02*
X02817Y00417D01*
X02836Y00436*
X02847D02*
X02851Y00432D01*
X02856Y00449D02*
X02862Y00443D01*
X02866Y0046D02*
X02872Y00454D01*
X02879Y00468D02*
X02883Y00464D01*
X02879Y00479D02*
D01*
X02881Y00481*
X02821Y00407D02*
X02821D01*
X02821Y00407D02*
X02821Y00407D01*
X02803Y00407D02*
Y00407D01*
X02811Y0043D02*
X0287Y00489D01*
X02811Y0043D02*
X02811Y0043D01*
X02809Y00393D02*
X02809Y00393D01*
X02819Y00407D02*
X02821D01*
X02816Y00411D02*
X02818Y00406D01*
X02872Y00492D02*
Y0077D01*
X02881Y00481D02*
X02881Y00482D01*
X02735Y00407D02*
X02735Y00407D01*
X02736Y00408D02*
X0274Y00423D01*
Y00435*
X02733Y00443D02*
D01*
Y00458D02*
X02734D01*
X02732Y00473D02*
X02734D01*
X02732Y00488D02*
X02734D01*
X02731Y00503D02*
X02734D01*
X02731Y00518D02*
X02733D01*
X0274Y00525D02*
Y00543D01*
Y00775*
X02411Y00364D02*
X02419Y00362D01*
D01*
X02428Y00369D02*
Y00372D01*
X02443Y00361D02*
Y00372D01*
X02449Y00354D02*
D01*
X02449Y00354*
X0246*
X02468*
X02535*
X02444Y00505D02*
Y00562D01*
X02452Y00498D02*
X02456D01*
X02442Y00483D02*
X02456D01*
X02442Y00468D02*
X02458D01*
X02452Y00453D02*
X02458D01*
X02444Y00428D02*
Y00445D01*
Y00562D02*
Y00651D01*
Y00423D02*
Y00428D01*
X02446Y00419D02*
X02453Y00414D01*
X02883Y00509D02*
Y0077D01*
X02751Y00422D02*
Y00775D01*
X02449Y00343D02*
X02535D01*
X02617Y00466D02*
Y00775D01*
X02606Y00467D02*
Y00775D01*
X02476Y0074D02*
X02684Y00947D01*
X02484Y00732D02*
X02693Y00941D01*
X02453Y00414D02*
X02453Y00414D01*
X02466Y0073D02*
X02466Y0073D01*
X02469Y0041D02*
X02469Y0041D01*
X02469Y0041*
X02883Y00485D02*
Y00509D01*
X02893Y00795D02*
Y00795D01*
X02848Y00403D02*
X02849D01*
X02842Y00396D02*
Y00397D01*
X02665Y00405D02*
X02671Y00399D01*
D01*
X02751Y00422D02*
Y00422D01*
X02704Y00405D02*
D01*
X02814Y00941D02*
X02895Y0086D01*
X02466Y0073D02*
X02476Y0074D01*
X02474Y00722D02*
X02484Y00732D01*
X02759Y00795D02*
Y00795D01*
Y00795D02*
D01*
X02732D02*
Y00795D01*
X02352Y00404D02*
X02359D01*
X02364Y00397D02*
Y00399D01*
X02543Y00346D02*
X02585Y00388D01*
X02625Y00795D02*
D01*
Y00795D01*
Y00795D02*
D01*
X0238Y00404D02*
X02388D01*
X02375Y00399D02*
D01*
X02377Y00396D02*
X02397Y00376D01*
X02535Y00354D02*
X02577Y00396D01*
X02598Y00795D02*
Y00795D01*
X02367Y0039D02*
X02389Y00368D01*
X02823Y00973D02*
X02826Y00976D01*
X02799D02*
X028Y00974D01*
X02823Y00947D02*
X02917Y00854D01*
X02826Y00976D02*
Y00976D01*
X02799Y00976D02*
Y00976D01*
X02689Y0096D02*
D01*
X02681Y00976D02*
X02684Y00973D01*
X02707Y00974D02*
X02708Y00976D01*
X02681D02*
Y00976D01*
X02708Y00976D02*
Y00976D01*
G54D153*
X01849Y00271D02*
Y03701D01*
G54D159*
X04327Y02307D03*
G54D161*
X05578Y0089D03*
Y02489D03*
X04062Y02595D03*
G54D169*
X02043Y04257D03*
X01457Y04253D03*
G54D171*
X02494Y02661D03*
X02692Y02721D03*
X02511Y00405D03*
X0298Y00409D03*
X02821Y00407D03*
X02469Y0041D03*
X02854Y00405D03*
X02665D03*
X02704D03*
X0235D03*
X02389D03*
X03019D03*
X02732Y00795D03*
X02681Y00976D03*
X02708D03*
X02625Y00795D03*
X02598D03*
X02826Y00976D03*
X02799D03*
X02759Y00795D03*
X02862D03*
X02893D03*
X02475Y02291D03*
X03894Y01566D03*
X01754Y02126D03*
X03197Y01714D03*
X03439Y0187D03*
X03298Y01971D03*
X02985Y02287D03*
X02702Y02289D03*
X02272Y02463D03*
X01719Y01536D03*
X02942Y02286D03*
X01568Y02067D03*
X03773Y01666D03*
X02599Y02436D03*
X02894Y02431D03*
X02579Y02281D03*
X01619Y02121D03*
X02726Y02293D03*
X01884Y02071D03*
X0292Y02428D03*
X0245Y02282D03*
X03252Y01661D03*
X03392Y01871D03*
X02409Y02283D03*
X03549Y01441D03*
X02624Y02461D03*
X03834Y01481D03*
X03864Y01511D03*
X03924Y01536D03*
X03329Y01826D03*
X02645Y02274D03*
X02665Y02291D03*
X03803Y01691D03*
X03224Y01661D03*
X02252Y02613D03*
X01393Y01816D03*
X0099Y00687D03*
X03197Y0297D03*
X03491Y03103D03*
X0323Y03235D03*
X03358Y03448D03*
X03068Y03395D03*
X03056Y01811D03*
X02254Y03536D03*
X02579Y03486D03*
X02389Y03481D03*
X02434Y03546D03*
X02634Y03406D03*
X02004Y01336D03*
X02028Y01361D03*
X02549Y01755D03*
X02462Y03172D03*
X02146Y04103D03*
X02253Y04086D03*
X01345Y04175D03*
X04039Y02406D03*
X03263Y03303D03*
X01852Y00255D03*
X01832Y00287D03*
X01852D03*
X02231Y02584D03*
X05577Y02214D03*
X02694Y01481D03*
X02384Y01941D03*
X03744Y03261D03*
X05634Y02236D03*
X02626Y0177D03*
X03939Y03121D03*
X02604Y01734D03*
X02299Y01916D03*
X02579Y0179D03*
X02259Y03261D03*
X03374Y03273D03*
X03368Y0305D03*
X03806Y03235D03*
X01459Y03147D03*
X0144Y03557D03*
X03623Y02587D03*
X03622Y03486D03*
X03491Y03297D03*
X03542Y03319D03*
X03344Y02996D03*
X03653Y03293D03*
X03394Y03447D03*
X03436Y03457D03*
X03589Y01711D03*
X02478Y00937D03*
X02206Y01298D03*
X02205Y032D03*
X02502Y01316D03*
X02525Y02463D03*
X03342Y02263D03*
X03498Y02341D03*
X02429Y02621D03*
X02446Y01437D03*
X02409Y01967D03*
X02643Y01616D03*
X02666Y0164D03*
X01884Y03601D03*
X01754Y03661D03*
X01549Y03621D03*
X01574Y03596D03*
X02084Y03896D03*
X02083Y01411D03*
X02059Y01386D03*
Y03871D03*
X02029Y03836D03*
X02004Y03816D03*
X02234Y03506D03*
X02993Y03751D03*
X03014Y03831D03*
X02894Y01561D03*
X02919Y01536D03*
X02274Y01506D03*
X02719Y01591D03*
X03724Y01675D03*
X01779Y04156D03*
X03504Y04086D03*
X03854Y03151D03*
X03829Y03176D03*
X03799Y03201D03*
X03302Y03344D03*
X03469Y03456D03*
X01849Y03701D03*
M02*